# SCM (Grand Teton) — schematic netlist excerpt (pin names and nets, part order shuffled) for the footprints in the layout excerpt that follows; sources: Cadence DE-HDL packaged netlist, KiCad conversion of 12092022_DA0F0TMDCD0_F0T_Management_Board_D_brd_V3_OCP.brd

C195  Q_CAP  1UF 25V 10% X6S  pkg C0402  page 41 : A = VCCIO4 ; B = GND
C71  Q_CAP  0.1UF 25V 10% X7R  pkg 0402  page 16 : A = P1V2_STBY_MVDD_CK ; B = GND

(kicad_pcb
	(version 20260206)
	(generator "pcbnew")
	(generator_version "10.0")
	(general
		(thickness 1.6)
		(legacy_teardrops no)
	)
	(paper "A4")
	(title_block
		(title "12092022_DA0F0TMDCD0_F0T_Management_Board_D_brd_V3_OCP.brd")
		(comment 1 "Grand Teton / footprints 897-898 of 1440")
	)
	(layers
		(0 "F.Cu" signal "TOP")
		(4 "In1.Cu" signal "GND")
		(6 "In2.Cu" signal "IN1")
		(8 "In3.Cu" signal "GND1")
		(10 "In4.Cu" signal "IN2")
		(12 "In5.Cu" signal "VCC")
		(14 "In6.Cu" signal "VCC1")
		(16 "In7.Cu" signal "IN3")
		(18 "In8.Cu" signal "GND2")
		(20 "In9.Cu" signal "IN4")
		(22 "In10.Cu" signal "GND3")
		(2 "B.Cu" signal "BOTTOM")
		(9 "F.Adhes" user "F.Adhesive")
		(11 "B.Adhes" user "B.Adhesive")
		(13 "F.Paste" user "Package Geometry/Pastemask Top")
		(15 "B.Paste" user "Package Geometry/Pastemask Bottom")
		(5 "F.SilkS" user "Ref Des/Silkscreen Top")
		(7 "B.SilkS" user "Ref Des/Silkscreen Bottom")
		(1 "F.Mask" user "Board Geometry/Soldermask Top")
		(3 "B.Mask" user "Board Geometry/Soldermask Bottom")
		(17 "Dwgs.User" user "User.Drawings")
		(19 "Cmts.User" user "User.Comments")
		(21 "Eco1.User" user "User.Eco1")
		(23 "Eco2.User" user "User.Eco2")
		(25 "Edge.Cuts" user "Board Geometry/Outline")
		(27 "Margin" user)
		(31 "F.CrtYd" user "Package Geometry/Place Bound Top")
		(29 "B.CrtYd" user "Package Geometry/Place Bound Bottom")
		(35 "F.Fab" user "Ref Des/Assembly Top")
		(33 "B.Fab" user "Ref Des/Assembly Bottom")
	)
	(footprint ""
		(layer "B.Cu")
		(at 60.45835 -47.844964 90)
		(property "Reference" "C71"
			(at 0 0 90)
			(layer "B.SilkS")
			(hide yes)
			(effects
				(font
					(size 1.27 1.27)
				)
				(justify mirror)
			)
		)
		(property "Value" ""
			(at 0 0 90)
			(layer "B.Fab")
			(effects
				(font
					(size 1.27 1.27)
				)
				(justify mirror)
			)
		)
		(duplicate_pad_numbers_are_jumpers no)
		(fp_line
			(start 0.7874 -0.4064)
			(end -0.7874 -0.4064)
			(stroke
				(width 0.1524)
				(type default)
			)
			(layer "B.SilkS")
		)
		(fp_line
			(start -0.7874 -0.4064)
			(end -0.7874 0.4064)
			(stroke
				(width 0.1524)
				(type default)
			)
			(layer "B.SilkS")
		)
		(fp_line
			(start 0.7874 0.4064)
			(end 0.7874 -0.4064)
			(stroke
				(width 0.1524)
				(type default)
			)
			(layer "B.SilkS")
		)
		(fp_line
			(start -0.7874 0.4064)
			(end 0.7874 0.4064)
			(stroke
				(width 0.1524)
				(type default)
			)
			(layer "B.SilkS")
		)
		(fp_line
			(start 0.67945 -0.305054)
			(end 0.12065 -0.305054)
			(stroke
				(width 0.1)
				(type default)
			)
			(layer "B.Fab")
		)
		(fp_line
			(start 0.12065 -0.305054)
			(end 0.12065 -0.2794)
			(stroke
				(width 0.1)
				(type default)
			)
			(layer "B.Fab")
		)
		(fp_line
			(start -0.12065 -0.3048)
			(end -0.67945 -0.3048)
			(stroke
				(width 0.1)
				(type default)
			)
			(layer "B.Fab")
		)
		(fp_line
			(start -0.67945 -0.3048)
			(end -0.67945 0.3048)
			(stroke
				(width 0.1)
				(type default)
			)
			(layer "B.Fab")
		)
		(fp_line
			(start 0.12065 -0.2794)
			(end -0.12065 -0.2794)
			(stroke
				(width 0.1)
				(type default)
			)
			(layer "B.Fab")
		)
		(fp_line
			(start -0.12065 -0.2794)
			(end -0.12065 -0.3048)
			(stroke
				(width 0.1)
				(type default)
			)
			(layer "B.Fab")
		)
		(fp_line
			(start 0.12065 0.2794)
			(end 0.12065 0.3048)
			(stroke
				(width 0.1)
				(type default)
			)
			(layer "B.Fab")
		)
		(fp_line
			(start -0.120396 0.2794)
			(end 0.12065 0.2794)
			(stroke
				(width 0.1)
				(type default)
			)
			(layer "B.Fab")
		)
		(fp_line
			(start 0.67945 0.3048)
			(end 0.67945 -0.305054)
			(stroke
				(width 0.1)
				(type default)
			)
			(layer "B.Fab")
		)
		(fp_line
			(start 0.12065 0.3048)
			(end 0.67945 0.3048)
			(stroke
				(width 0.1)
				(type default)
			)
			(layer "B.Fab")
		)
		(fp_line
			(start -0.120396 0.3048)
			(end -0.120396 0.2794)
			(stroke
				(width 0.1)
				(type default)
			)
			(layer "B.Fab")
		)
		(fp_line
			(start -0.67945 0.3048)
			(end -0.120396 0.3048)
			(stroke
				(width 0.1)
				(type default)
			)
			(layer "B.Fab")
		)
		(pad "1" smd circle
			(at 0.40005 0 270)
			(size 0 0)
			(layers "B.Cu" "B.Mask" "B.Paste")
			(net "P1V2_STBY_MVDD_CK")
		)
		(pad "2" smd circle
			(at -0.40005 0 270)
			(size 0 0)
			(layers "B.Cu" "B.Mask" "B.Paste")
			(net "GND")
		)
	)
	(footprint ""
		(layer "B.Cu")
		(at 24.384 -94.234 180)
		(property "Reference" "C195"
			(at 0 0 0)
			(layer "B.SilkS")
			(hide yes)
			(effects
				(font
					(size 1.27 1.27)
				)
				(justify mirror)
			)
		)
		(property "Value" ""
			(at 0 0 0)
			(layer "B.Fab")
			(effects
				(font
					(size 1.27 1.27)
				)
				(justify mirror)
			)
		)
		(duplicate_pad_numbers_are_jumpers no)
		(fp_line
			(start 0.69215 0.2921)
			(end 0.69215 -0.2921)
			(stroke
				(width 0.1524)
				(type default)
			)
			(layer "B.SilkS")
		)
		(fp_line
			(start 0.69215 -0.2921)
			(end -0.69215 -0.2921)
			(stroke
				(width 0.1524)
				(type default)
			)
			(layer "B.SilkS")
		)
		(fp_line
			(start -0.69215 0.2921)
			(end 0.69215 0.2921)
			(stroke
				(width 0.1524)
				(type default)
			)
			(layer "B.SilkS")
		)
		(fp_line
			(start -0.69215 -0.2921)
			(end -0.69215 0.2921)
			(stroke
				(width 0.1524)
				(type default)
			)
			(layer "B.SilkS")
		)
		(fp_line
			(start 0.51435 0.2794)
			(end 0.51435 -0.2794)
			(stroke
				(width 0.1)
				(type default)
			)
			(layer "B.Fab")
		)
		(fp_line
			(start 0.51435 -0.2794)
			(end -0.51435 -0.2794)
			(stroke
				(width 0.1)
				(type default)
			)
			(layer "B.Fab")
		)
		(fp_line
			(start -0.51435 0.2794)
			(end 0.51435 0.2794)
			(stroke
				(width 0.1)
				(type default)
			)
			(layer "B.Fab")
		)
		(fp_line
			(start -0.51435 -0.2794)
			(end -0.51435 0.2794)
			(stroke
				(width 0.1)
				(type default)
			)
			(layer "B.Fab")
		)
		(pad "1" smd circle
			(at 0.40005 0)
			(size 0 0)
			(layers "B.Cu" "B.Mask" "B.Paste")
			(net "VCCIO4")
		)
		(pad "2" smd circle
			(at -0.40005 0)
			(size 0 0)
			(layers "B.Cu" "B.Mask" "B.Paste")
			(net "GND")
		)
		(zone
			(layer "B.Cu")
			(hatch none 0.5)
			(connect_pads
				(clearance 0)
			)
			(min_thickness 0.25)
			(keepout
				(tracks not_allowed)
				(vias allowed)
				(pads allowed)
				(copperpour not_allowed)
				(footprints allowed)
			)
			(placement
				(enabled no)
				(sheetname "")
			)
			(fill
				(thermal_gap 0.5)
				(thermal_bridge_width 0.5)
				(island_removal_mode 0)
			)
			(polygon
				(pts
					(xy 24.1935 -94.32163) (xy 24.28494 -94.379796) (xy 24.48433 -94.379796) (xy 24.5745 -94.32163)
					(xy 24.5745 -94.14637) (xy 24.48433 -94.08795) (xy 24.28494 -94.08795) (xy 24.1935 -94.146116)
				)
			)
		)
	)
)
